# BASEBOARD_FAB2 (Tioga Pass) — schematic netlist excerpt (pin names and nets, part order shuffled) for the footprints in the layout excerpt that follows; sources: Cadence DE-HDL packaged netlist, KiCad conversion of Wiwynn_Tioga_Pass_MB.brd

C3T6  CAPP  68UF 16V 20% TANT  pkg 3018  page 195 : A = P12V_STBY ; B = GND
C3T5  CAP_A  0.01UF 25V 10% X7R  pkg 0402V  page 153 : A = P3V3_STBY ; B = GND
C1L1  CAP  1.0UF 16V 10% X6S  pkg 0402  page 112 : A = P3V3_STBY ; B = GND

(kicad_pcb
	(version 20260206)
	(generator "pcbnew")
	(generator_version "10.0")
	(general
		(thickness 1.6)
		(legacy_teardrops no)
	)
	(paper "A4")
	(title_block
		(title "Wiwynn_Tioga_Pass_MB.brd")
		(comment 1 "Tioga Pass / footprints 4360-4362 of 4770")
	)
	(layers
		(0 "F.Cu" signal "TOP")
		(4 "In1.Cu" signal "L2GND")
		(6 "In2.Cu" signal "L3")
		(8 "In3.Cu" signal "L4GND")
		(10 "In4.Cu" signal "L5")
		(12 "In5.Cu" signal "L6GND")
		(14 "In6.Cu" signal "L7VCC")
		(16 "In7.Cu" signal "L8VCC")
		(18 "In8.Cu" signal "L9GND")
		(20 "In9.Cu" signal "L10")
		(22 "In10.Cu" signal "L11GND")
		(24 "In11.Cu" signal "L12")
		(26 "In12.Cu" signal "L13GND")
		(2 "B.Cu" signal "BOTTOM")
		(9 "F.Adhes" user "F.Adhesive")
		(11 "B.Adhes" user "B.Adhesive")
		(13 "F.Paste" user "Package Geometry/Pastemask Top")
		(15 "B.Paste" user "Package Geometry/Pastemask Bottom")
		(5 "F.SilkS" user "Ref Des/Silkscreen Top")
		(7 "B.SilkS" user "Ref Des/Silkscreen Bottom")
		(1 "F.Mask" user "Board Geometry/Soldermask Top")
		(3 "B.Mask" user "Board Geometry/Soldermask Bottom")
		(17 "Dwgs.User" user "User.Drawings")
		(19 "Cmts.User" user "User.Comments")
		(21 "Eco1.User" user "User.Eco1")
		(23 "Eco2.User" user "User.Eco2")
		(25 "Edge.Cuts" user "Board Geometry/Outline")
		(27 "Margin" user)
		(31 "F.CrtYd" user "Package Geometry/Place Bound Top")
		(29 "B.CrtYd" user "Package Geometry/Place Bound Bottom")
		(35 "F.Fab" user "Ref Des/Assembly Top")
		(33 "B.Fab" user "Ref Des/Assembly Bottom")
	)
	(footprint ""
		(layer "B.Cu")
		(at 357.378 -33.782)
		(property "Reference" "C3T6"
			(at 3.27533 3.048 270)
			(unlocked yes)
			(layer "B.SilkS")
			(effects
				(font
					(size 0.7874 0.5842)
					(thickness 0.1524)
				)
				(justify mirror)
			)
		)
		(property "Value" ""
			(at 0 0 0)
			(layer "B.Fab")
			(effects
				(font
					(size 1.27 1.27)
				)
				(justify mirror)
			)
		)
		(duplicate_pad_numbers_are_jumpers no)
		(fp_line
			(start -2.504948 -1.616456)
			(end -2.504948 1.633728)
			(stroke
				(width 0.1524)
				(type default)
			)
			(layer "B.SilkS")
		)
		(fp_line
			(start -2.504948 1.633728)
			(end -1.6002 1.633728)
			(stroke
				(width 0.1524)
				(type default)
			)
			(layer "B.SilkS")
		)
		(fp_line
			(start -2.286 7.366)
			(end -2.286 1.63195)
			(stroke
				(width 0.1524)
				(type default)
			)
			(layer "B.SilkS")
		)
		(fp_line
			(start -2.286 7.366)
			(end -1.600708 7.366)
			(stroke
				(width 0.1524)
				(type default)
			)
			(layer "B.SilkS")
		)
		(fp_line
			(start -1.6002 -1.616456)
			(end -2.504948 -1.616456)
			(stroke
				(width 0.1524)
				(type default)
			)
			(layer "B.SilkS")
		)
		(fp_line
			(start 1.6002 -1.616456)
			(end 2.563114 -1.616456)
			(stroke
				(width 0.1524)
				(type default)
			)
			(layer "B.SilkS")
		)
		(fp_line
			(start 2.286 7.366)
			(end 1.60147 7.366)
			(stroke
				(width 0.1524)
				(type default)
			)
			(layer "B.SilkS")
		)
		(fp_line
			(start 2.286 7.366)
			(end 2.286 1.632712)
			(stroke
				(width 0.1524)
				(type default)
			)
			(layer "B.SilkS")
		)
		(fp_line
			(start 2.563114 -1.616456)
			(end 2.563114 1.633728)
			(stroke
				(width 0.1524)
				(type default)
			)
			(layer "B.SilkS")
		)
		(fp_line
			(start 2.563114 1.633728)
			(end 1.6002 1.633728)
			(stroke
				(width 0.1524)
				(type default)
			)
			(layer "B.SilkS")
		)
		(fp_rect
			(start 2.286 7.366)
			(end -2.286 -0.254)
			(stroke
				(width 0)
				(type default)
			)
			(fill no)
			(layer "B.CrtYd")
		)
		(fp_line
			(start -2.286 -0.254)
			(end -2.286 7.366)
			(stroke
				(width 0.1)
				(type default)
			)
			(layer "B.Fab")
		)
		(fp_line
			(start -2.286 7.366)
			(end 2.286 7.366)
			(stroke
				(width 0.1)
				(type default)
			)
			(layer "B.Fab")
		)
		(fp_line
			(start 2.286 -0.254)
			(end -2.286 -0.254)
			(stroke
				(width 0.1)
				(type default)
			)
			(layer "B.Fab")
		)
		(fp_line
			(start 2.286 7.366)
			(end 2.286 -0.254)
			(stroke
				(width 0.1)
				(type default)
			)
			(layer "B.Fab")
		)
		(pad "1" smd rect
			(at 0 0 180)
			(size 2.54 3.048)
			(layers "B.Cu" "B.Mask" "B.Paste")
			(net "P12V_STBY")
		)
		(pad "2" smd rect
			(at 0 7.112 180)
			(size 2.54 3.048)
			(layers "B.Cu" "B.Mask" "B.Paste")
			(net "GND")
		)
	)
	(footprint ""
		(layer "B.Cu")
		(at 459.359 -153.924 90)
		(property "Reference" "C1L1"
			(at 0 0 90)
			(layer "B.SilkS")
			(hide yes)
			(effects
				(font
					(size 1.27 1.27)
				)
				(justify mirror)
			)
		)
		(property "Value" ""
			(at 0 0 90)
			(layer "B.Fab")
			(effects
				(font
					(size 1.27 1.27)
				)
				(justify mirror)
			)
		)
		(duplicate_pad_numbers_are_jumpers no)
		(fp_poly
			(pts
				(xy -0.3048 -0.1016) (xy -0.3048 0.9906) (xy 0.3048 0.9906) (xy 0.3048 -0.1016)
			)
			(stroke
				(width 0)
				(type default)
			)
			(fill no)
			(layer "B.CrtYd")
		)
		(fp_line
			(start 0.3048 -0.1016)
			(end 0.3048 0.9906)
			(stroke
				(width 0.1)
				(type default)
			)
			(layer "B.Fab")
		)
		(fp_line
			(start -0.3048 -0.1016)
			(end 0.3048 -0.1016)
			(stroke
				(width 0.1)
				(type default)
			)
			(layer "B.Fab")
		)
		(fp_line
			(start 0.3048 0.9906)
			(end -0.3048 0.9906)
			(stroke
				(width 0.1)
				(type default)
			)
			(layer "B.Fab")
		)
		(fp_line
			(start -0.3048 0.9906)
			(end -0.3048 -0.1016)
			(stroke
				(width 0.1)
				(type default)
			)
			(layer "B.Fab")
		)
		(pad "1" smd rect
			(at 0 0 270)
			(size 0.508 0.508)
			(layers "B.Cu" "B.Mask" "B.Paste")
			(net "P3V3_STBY")
		)
		(pad "2" smd rect
			(at 0 0.889 270)
			(size 0.508 0.508)
			(layers "B.Cu" "B.Mask" "B.Paste")
			(net "GND")
		)
		(zone
			(layer "B.Cu")
			(hatch none 0.5)
			(connect_pads
				(clearance 0)
			)
			(min_thickness 0.25)
			(keepout
				(tracks allowed)
				(vias not_allowed)
				(pads allowed)
				(copperpour not_allowed)
				(footprints allowed)
			)
			(placement
				(enabled no)
				(sheetname "")
			)
			(fill
				(thermal_gap 0.5)
				(thermal_bridge_width 0.5)
				(island_removal_mode 0)
			)
			(polygon
				(pts
					(xy 459.613 -154.178) (xy 459.613 -153.67) (xy 459.994 -153.67) (xy 459.994 -154.178)
				)
			)
		)
		(zone
			(layer "B.Cu")
			(hatch none 0.5)
			(connect_pads
				(clearance 0)
			)
			(min_thickness 0.25)
			(keepout
				(tracks not_allowed)
				(vias allowed)
				(pads allowed)
				(copperpour not_allowed)
				(footprints allowed)
			)
			(placement
				(enabled no)
				(sheetname "")
			)
			(fill
				(thermal_gap 0.5)
				(thermal_bridge_width 0.5)
				(island_removal_mode 0)
			)
			(polygon
				(pts
					(xy 459.994 -154.178) (xy 459.994 -153.67) (xy 459.613 -153.67) (xy 459.613 -154.178)
				)
			)
		)
	)
	(footprint ""
		(layer "B.Cu")
		(at 401.20316 -54.25186)
		(property "Reference" "C3T5"
			(at 0 0 0)
			(layer "B.SilkS")
			(hide yes)
			(effects
				(font
					(size 1.27 1.27)
				)
				(justify mirror)
			)
		)
		(property "Value" ""
			(at 0 0 0)
			(layer "B.Fab")
			(effects
				(font
					(size 1.27 1.27)
				)
				(justify mirror)
			)
		)
		(duplicate_pad_numbers_are_jumpers no)
		(fp_poly
			(pts
				(xy -0.3048 -0.1016) (xy -0.3048 0.9906) (xy 0.3048 0.9906) (xy 0.3048 -0.1016)
			)
			(stroke
				(width 0)
				(type default)
			)
			(fill no)
			(layer "B.CrtYd")
		)
		(fp_line
			(start -0.3048 -0.1016)
			(end 0.3048 -0.1016)
			(stroke
				(width 0.1)
				(type default)
			)
			(layer "B.Fab")
		)
		(fp_line
			(start -0.3048 0.9906)
			(end -0.3048 -0.1016)
			(stroke
				(width 0.1)
				(type default)
			)
			(layer "B.Fab")
		)
		(fp_line
			(start 0.3048 -0.1016)
			(end 0.3048 0.9906)
			(stroke
				(width 0.1)
				(type default)
			)
			(layer "B.Fab")
		)
		(fp_line
			(start 0.3048 0.9906)
			(end -0.3048 0.9906)
			(stroke
				(width 0.1)
				(type default)
			)
			(layer "B.Fab")
		)
		(pad "1" smd rect
			(at 0 0 180)
			(size 0.508 0.508)
			(layers "B.Cu" "B.Mask" "B.Paste")
			(net "P3V3_STBY")
		)
		(pad "2" smd rect
			(at 0 0.889 180)
			(size 0.508 0.508)
			(layers "B.Cu" "B.Mask" "B.Paste")
			(net "GND")
		)
		(zone
			(layer "B.Cu")
			(hatch none 0.5)
			(connect_pads
				(clearance 0)
			)
			(min_thickness 0.25)
			(keepout
				(tracks allowed)
				(vias not_allowed)
				(pads allowed)
				(copperpour not_allowed)
				(footprints allowed)
			)
			(placement
				(enabled no)
				(sheetname "")
			)
			(fill
				(thermal_gap 0.5)
				(thermal_bridge_width 0.5)
				(island_removal_mode 0)
			)
			(polygon
				(pts
					(xy 401.45716 -53.99786) (xy 400.94916 -53.99786) (xy 400.94916 -53.61686) (xy 401.45716 -53.61686)
				)
			)
		)
		(zone
			(layer "B.Cu")
			(hatch none 0.5)
			(connect_pads
				(clearance 0)
			)
			(min_thickness 0.25)
			(keepout
				(tracks not_allowed)
				(vias allowed)
				(pads allowed)
				(copperpour not_allowed)
				(footprints allowed)
			)
			(placement
				(enabled no)
				(sheetname "")
			)
			(fill
				(thermal_gap 0.5)
				(thermal_bridge_width 0.5)
				(island_removal_mode 0)
			)
			(polygon
				(pts
					(xy 401.45716 -53.61686) (xy 400.94916 -53.61686) (xy 400.94916 -53.99786) (xy 401.45716 -53.99786)
				)
			)
		)
	)
)
